# T6G (Grand Teton) — schematic netlist excerpt (pin names and nets, part order shuffled) for the footprints in the layout excerpt that follows; sources: Cadence DE-HDL packaged netlist, KiCad conversion of 04192023_DAF0TMB3IC0_F0TG_MB_C_brd_V02_OCP.brd

R108  Q_RES  1K 1% EMPTY  pkg 0402LF  page 103 : A = P3V3 ; B = PWRGD_CHF_CPU1_DIMM

X8011  TP_TDR_4P_FTS  TP_TDR_4P_DIP EMPTY  pkg TH  page 260
  S1  = TDR_DIFF_85_IN4_DN
  P1  = T1_GND
  P2  = T1_GND
  S2  = TDR_DIFF_85_IN4_DP

(kicad_pcb
	(version 20260206)
	(generator "pcbnew")
	(generator_version "10.0")
	(general
		(thickness 1.6)
		(legacy_teardrops no)
	)
	(paper "A4")
	(title_block
		(title "04192023_DAF0TMB3IC0_F0TG_MB_C_brd_V02_OCP.brd")
		(comment 1 "Grand Teton / footprints 5549-5550 of 8354")
	)
	(layers
		(0 "F.Cu" signal "TOP")
		(4 "In1.Cu" signal "GND")
		(6 "In2.Cu" signal "IN1")
		(8 "In3.Cu" signal "GND1")
		(10 "In4.Cu" signal "IN2")
		(12 "In5.Cu" signal "GND2")
		(14 "In6.Cu" signal "IN3")
		(16 "In7.Cu" signal "GND3")
		(18 "In8.Cu" signal "VCC")
		(20 "In9.Cu" signal "VCC1")
		(22 "In10.Cu" signal "GND4")
		(24 "In11.Cu" signal "IN4")
		(26 "In12.Cu" signal "GND5")
		(28 "In13.Cu" signal "IN5")
		(30 "In14.Cu" signal "GND6")
		(32 "In15.Cu" signal "IN6")
		(34 "In16.Cu" signal "GND7")
		(2 "B.Cu" signal "BOTTOM")
		(9 "F.Adhes" user "F.Adhesive")
		(11 "B.Adhes" user "B.Adhesive")
		(13 "F.Paste" user "Package Geometry/Pastemask Top")
		(15 "B.Paste" user "Package Geometry/Pastemask Bottom")
		(5 "F.SilkS" user "Ref Des/Silkscreen Top")
		(7 "B.SilkS" user "Ref Des/Silkscreen Bottom")
		(1 "F.Mask" user "Board Geometry/Soldermask Top")
		(3 "B.Mask" user "Board Geometry/Soldermask Bottom")
		(17 "Dwgs.User" user "User.Drawings")
		(19 "Cmts.User" user "User.Comments")
		(21 "Eco1.User" user "User.Eco1")
		(23 "Eco2.User" user "User.Eco2")
		(25 "Edge.Cuts" user "Board Geometry/Outline")
		(27 "Margin" user)
		(31 "F.CrtYd" user "Package Geometry/Place Bound Top")
		(29 "B.CrtYd" user "Package Geometry/Place Bound Bottom")
		(35 "F.Fab" user "Ref Des/Assembly Top")
		(33 "B.Fab" user "Ref Des/Assembly Bottom")
	)
	(footprint ""
		(layer "B.Cu")
		(at 14.097762 -192.362328 -90)
		(property "Reference" "R108"
			(at 0 0 90)
			(layer "B.SilkS")
			(hide yes)
			(effects
				(font
					(size 1.27 1.27)
				)
				(justify mirror)
			)
		)
		(property "Value" ""
			(at 0 0 90)
			(layer "B.Fab")
			(effects
				(font
					(size 1.27 1.27)
				)
				(justify mirror)
			)
		)
		(duplicate_pad_numbers_are_jumpers no)
		(fp_line
			(start -0.7874 0.4064)
			(end 0.7874 0.4064)
			(stroke
				(width 0.1524)
				(type default)
			)
			(layer "B.SilkS")
		)
		(fp_line
			(start 0.7874 0.4064)
			(end 0.7874 -0.4064)
			(stroke
				(width 0.1524)
				(type default)
			)
			(layer "B.SilkS")
		)
		(fp_line
			(start -0.7874 -0.4064)
			(end -0.7874 0.4064)
			(stroke
				(width 0.1524)
				(type default)
			)
			(layer "B.SilkS")
		)
		(fp_line
			(start 0.7874 -0.4064)
			(end -0.7874 -0.4064)
			(stroke
				(width 0.1524)
				(type default)
			)
			(layer "B.SilkS")
		)
		(fp_line
			(start -0.67945 0.3048)
			(end -0.120396 0.3048)
			(stroke
				(width 0.1)
				(type default)
			)
			(layer "B.Fab")
		)
		(fp_line
			(start -0.120396 0.3048)
			(end -0.120396 0.2794)
			(stroke
				(width 0.1)
				(type default)
			)
			(layer "B.Fab")
		)
		(fp_line
			(start 0.12065 0.3048)
			(end 0.67945 0.3048)
			(stroke
				(width 0.1)
				(type default)
			)
			(layer "B.Fab")
		)
		(fp_line
			(start 0.67945 0.3048)
			(end 0.67945 -0.305054)
			(stroke
				(width 0.1)
				(type default)
			)
			(layer "B.Fab")
		)
		(fp_line
			(start -0.120396 0.2794)
			(end 0.12065 0.2794)
			(stroke
				(width 0.1)
				(type default)
			)
			(layer "B.Fab")
		)
		(fp_line
			(start 0.12065 0.2794)
			(end 0.12065 0.3048)
			(stroke
				(width 0.1)
				(type default)
			)
			(layer "B.Fab")
		)
		(fp_line
			(start -0.12065 -0.2794)
			(end -0.12065 -0.3048)
			(stroke
				(width 0.1)
				(type default)
			)
			(layer "B.Fab")
		)
		(fp_line
			(start 0.12065 -0.2794)
			(end -0.12065 -0.2794)
			(stroke
				(width 0.1)
				(type default)
			)
			(layer "B.Fab")
		)
		(fp_line
			(start -0.67945 -0.3048)
			(end -0.67945 0.3048)
			(stroke
				(width 0.1)
				(type default)
			)
			(layer "B.Fab")
		)
		(fp_line
			(start -0.12065 -0.3048)
			(end -0.67945 -0.3048)
			(stroke
				(width 0.1)
				(type default)
			)
			(layer "B.Fab")
		)
		(fp_line
			(start 0.12065 -0.305054)
			(end 0.12065 -0.2794)
			(stroke
				(width 0.1)
				(type default)
			)
			(layer "B.Fab")
		)
		(fp_line
			(start 0.67945 -0.305054)
			(end 0.12065 -0.305054)
			(stroke
				(width 0.1)
				(type default)
			)
			(layer "B.Fab")
		)
		(pad "1" smd circle
			(at 0.40005 0 90)
			(size 0 0)
			(layers "B.Cu" "B.Mask" "B.Paste")
			(net "P3V3")
		)
		(pad "2" smd circle
			(at -0.40005 0 90)
			(size 0 0)
			(layers "B.Cu" "B.Mask" "B.Paste")
			(net "PWRGD_CHF_CPU1_DIMM")
		)
	)
	(footprint ""
		(layer "B.Cu")
		(at 517.258808 -142.892526 -90)
		(property "Reference" "X8011"
			(at 4.4577 -1.50495 270)
			(unlocked yes)
			(layer "B.SilkS")
			(effects
				(font
					(size 0.7874 0.5842)
					(thickness 0.1524)
				)
				(justify left mirror)
			)
		)
		(property "Value" ""
			(at 0 0 90)
			(layer "B.Fab")
			(effects
				(font
					(size 1.27 1.27)
				)
				(justify mirror)
			)
		)
		(property "Device Type" "TP_TDR_4P_FTS_TH-TP_TDR_4P_DIP,EMPTY,TP15"
			(at -1.30175 1.27 180)
			(unlocked yes)
			(layer "B.Fab")
			(hide yes)
			(effects
				(font
					(size 0.635 0.4064)
					(thickness 0.1524)
				)
				(justify mirror)
			)
		)
		(property "User Part Number" "N_A"
			(at -1.30175 1.27 180)
			(unlocked yes)
			(layer "Cmts.User")
			(hide yes)
			(effects
				(font
					(size 0.635 0.4064)
					(thickness 0.1524)
				)
				(justify mirror)
			)
		)
		(duplicate_pad_numbers_are_jumpers no)
		(fp_line
			(start -2.54 3.81)
			(end -2.54 3.6703)
			(stroke
				(width 0.1524)
				(type default)
			)
			(layer "B.SilkS")
		)
		(fp_line
			(start 0 3.81)
			(end -2.54 3.81)
			(stroke
				(width 0.1524)
				(type default)
			)
			(layer "B.SilkS")
		)
		(fp_line
			(start 0 3.175)
			(end 0 3.81)
			(stroke
				(width 0.1524)
				(type default)
			)
			(layer "B.SilkS")
		)
		(fp_line
			(start -2.54 1.4097)
			(end -2.54 1.1303)
			(stroke
				(width 0.1524)
				(type default)
			)
			(layer "B.SilkS")
		)
		(fp_line
			(start 0 0.635)
			(end 0 1.905)
			(stroke
				(width 0.1524)
				(type default)
			)
			(layer "B.SilkS")
		)
		(fp_line
			(start -2.54 -1.1303)
			(end -2.54 -1.27)
			(stroke
				(width 0.1524)
				(type default)
			)
			(layer "B.SilkS")
		)
		(fp_line
			(start -2.54 -1.27)
			(end 0 -1.27)
			(stroke
				(width 0.1524)
				(type default)
			)
			(layer "B.SilkS")
		)
		(fp_line
			(start 0 -1.27)
			(end 0 -0.635)
			(stroke
				(width 0.1524)
				(type default)
			)
			(layer "B.SilkS")
		)
		(fp_poly
			(pts
				(xy 0.761746 0) (xy 2.285746 -0.762) (xy 2.285746 0.762)
			)
			(stroke
				(width 0)
				(type default)
			)
			(fill yes)
			(layer "B.SilkS")
		)
		(fp_line
			(start -2.54 3.81)
			(end -2.54 -1.27)
			(stroke
				(width 0.1)
				(type default)
			)
			(layer "B.Fab")
		)
		(fp_line
			(start 0 3.81)
			(end -2.54 3.81)
			(stroke
				(width 0.1)
				(type default)
			)
			(layer "B.Fab")
		)
		(fp_line
			(start -2.54 -1.27)
			(end 0 -1.27)
			(stroke
				(width 0.1)
				(type default)
			)
			(layer "B.Fab")
		)
		(fp_line
			(start 0 -1.27)
			(end 0 3.81)
			(stroke
				(width 0.1)
				(type default)
			)
			(layer "B.Fab")
		)
		(fp_poly
			(pts
				(xy 0.761746 0) (xy 2.285746 -0.762) (xy 2.285746 0.762)
			)
			(stroke
				(width 0)
				(type default)
			)
			(fill yes)
			(layer "B.Fab")
		)
		(pad "1" thru_hole circle
			(at 0 0 90)
			(size 1.0033 1.0033)
			(drill 0.249936)
			(layers "*.Cu" "*.Mask")
			(remove_unused_layers no)
			(net "TDR_DIFF_85_IN4_DN")
			(clearance 0.10795)
			(padstack
				(mode front_inner_back)
				(layer "Inner"
					(shape circle)
					(size 0.8001 0.8001)
					(clearance 0.1524)
				)
				(layer "B.Cu"
					(shape circle)
					(size 1.0033 1.0033)
					(thermal_gap 0.10795)
					(clearance 0.10795)
				)
			)
		)
		(pad "2" thru_hole circle
			(at -2.54 0 90)
			(size 1.9939 1.9939)
			(drill 0.249936)
			(layers "*.Cu" "*.Mask")
			(remove_unused_layers no)
			(net "T1_GND")
			(clearance 0.10795)
			(padstack
				(mode front_inner_back)
				(layer "Inner"
					(shape circle)
					(size 0.8001 0.8001)
					(clearance 0.1524)
				)
				(layer "B.Cu"
					(shape circle)
					(size 1.9939 1.9939)
					(thermal_gap 0.10795)
					(clearance 0.10795)
				)
			)
		)
		(pad "3" thru_hole circle
			(at -2.54 2.54 90)
			(size 1.9939 1.9939)
			(drill 0.249936)
			(layers "*.Cu" "*.Mask")
			(remove_unused_layers no)
			(net "T1_GND")
			(clearance 0.10795)
			(padstack
				(mode front_inner_back)
				(layer "Inner"
					(shape circle)
					(size 0.8001 0.8001)
					(clearance 0.1524)
				)
				(layer "B.Cu"
					(shape circle)
					(size 1.9939 1.9939)
					(thermal_gap 0.10795)
					(clearance 0.10795)
				)
			)
		)
		(pad "4" thru_hole circle
			(at 0 2.54 90)
			(size 1.0033 1.0033)
			(drill 0.249936)
			(layers "*.Cu" "*.Mask")
			(remove_unused_layers no)
			(net "TDR_DIFF_85_IN4_DP")
			(clearance 0.10795)
			(padstack
				(mode front_inner_back)
				(layer "Inner"
					(shape circle)
					(size 0.8001 0.8001)
					(clearance 0.1524)
				)
				(layer "B.Cu"
					(shape circle)
					(size 1.0033 1.0033)
					(thermal_gap 0.10795)
					(clearance 0.10795)
				)
			)
		)
	)
)
